(kicad_pcb
	(version 20260206)
	(generator "pcbnew")
	(generator_version "10.0")
	(general
		(thickness 1.6)
		(legacy_teardrops no)
	)
	(paper "A4")
	(title_block
		(title "peb — Lightning_PEB_BRD.brd")
		(comment 1 "Lightning (Wiwynn / Facebook NVMe JBOF) / footprints 50-56 of 2563")
	)
	(layers
		(0 "F.Cu" signal "TOP")
		(4 "In1.Cu" signal "L2GND")
		(6 "In2.Cu" signal "L3")
		(8 "In3.Cu" signal "L4VCC")
		(10 "In4.Cu" signal "L5VCC")
		(12 "In5.Cu" signal "L6")
		(14 "In6.Cu" signal "L7GND")
		(2 "B.Cu" signal "BOTTOM")
		(9 "F.Adhes" user "F.Adhesive")
		(11 "B.Adhes" user "B.Adhesive")
		(13 "F.Paste" user "Package Geometry/Pastemask Top")
		(15 "B.Paste" user "Package Geometry/Pastemask Bottom")
		(5 "F.SilkS" user "Ref Des/Silkscreen Top")
		(7 "B.SilkS" user "Ref Des/Silkscreen Bottom")
		(1 "F.Mask" user "Board Geometry/Soldermask Top")
		(3 "B.Mask" user "Board Geometry/Soldermask Bottom")
		(17 "Dwgs.User" user "User.Drawings")
		(19 "Cmts.User" user "User.Comments")
		(21 "Eco1.User" user "User.Eco1")
		(23 "Eco2.User" user "User.Eco2")
		(25 "Edge.Cuts" user "Board Geometry/Outline")
		(27 "Margin" user)
		(31 "F.CrtYd" user "Package Geometry/Place Bound Top")
		(29 "B.CrtYd" user "Package Geometry/Place Bound Bottom")
		(35 "F.Fab" user "Ref Des/Assembly Top")
		(33 "B.Fab" user "Ref Des/Assembly Bottom")
	)
	(footprint ""
		(layer "F.Cu")
		(at 276.40915 -3.600958 90)
		(property "Reference" "R278"
			(at 0 0 90)
			(layer "F.SilkS")
			(hide yes)
			(effects
				(font
					(size 1.27 1.27)
				)
			)
		)
		(property "Value" "0R2J-2-GP"
			(at 0.064008 -3.993896 90)
			(unlocked yes)
			(layer "F.Fab")
			(hide yes)
			(effects
				(font
					(size 1.016 1.016)
					(thickness 0.1524)
				)
			)
		)
		(property "Device Type" "R402H16"
			(at 0.064008 -5.517896 90)
			(unlocked yes)
			(layer "F.Fab")
			(hide yes)
			(effects
				(font
					(size 1.016 1.016)
					(thickness 0.1524)
				)
			)
		)
		(duplicate_pad_numbers_are_jumpers no)
		(fp_line
			(start 0.508 -0.9398)
			(end -0.508 -0.9398)
			(stroke
				(width 0.1524)
				(type default)
			)
			(layer "F.SilkS")
		)
		(fp_line
			(start -0.508 -0.9398)
			(end -0.508 0.9398)
			(stroke
				(width 0.1524)
				(type default)
			)
			(layer "F.SilkS")
		)
		(fp_rect
			(start -0.508 0.9398)
			(end 0.508 -0.9398)
			(stroke
				(width 0)
				(type default)
			)
			(fill no)
			(layer "F.CrtYd")
		)
		(fp_rect
			(start -0.508 0.9398)
			(end 0.508 -0.9398)
			(stroke
				(width 0)
				(type default)
			)
			(fill no)
			(layer "F.Fab")
		)
		(pad "1" smd custom
			(at 0 -0.4445 90)
			(size 0.1397 0.1397)
			(layers "F.Cu" "F.Mask" "F.Paste")
			(net "MINISAS_CN16_B_I2C_INT#")
			(options
				(clearance outline)
				(anchor circle)
			)
			(primitives
				(gr_poly
					(pts
						(arc
							(start -0.1778 -0.2794)
							(mid -0.249642 -0.249642)
							(end -0.2794 -0.1778)
						)
						(arc
							(start -0.2794 0.1778)
							(mid -0.249642 0.249642)
							(end -0.1778 0.2794)
						)
						(arc
							(start 0.1778 0.2794)
							(mid 0.249642 0.249642)
							(end 0.2794 0.1778)
						)
						(arc
							(start 0.2794 -0.1778)
							(mid 0.249642 -0.249642)
							(end 0.1778 -0.2794)
						)
					)
					(width 0)
					(fill yes)
				)
			)
		)
		(pad "2" smd custom
			(at 0 0.4445 90)
			(size 0.1397 0.1397)
			(layers "F.Cu" "F.Mask" "F.Paste")
			(net "CLK_N_6")
			(options
				(clearance outline)
				(anchor circle)
			)
			(primitives
				(gr_poly
					(pts
						(arc
							(start -0.1778 -0.2794)
							(mid -0.249642 -0.249642)
							(end -0.2794 -0.1778)
						)
						(arc
							(start -0.2794 0.1778)
							(mid -0.249642 0.249642)
							(end -0.1778 0.2794)
						)
						(arc
							(start 0.1778 0.2794)
							(mid 0.249642 0.249642)
							(end 0.2794 0.1778)
						)
						(arc
							(start 0.2794 -0.1778)
							(mid 0.249642 -0.249642)
							(end 0.1778 -0.2794)
						)
					)
					(width 0)
					(fill yes)
				)
			)
		)
	)
	(footprint ""
		(layer "F.Cu")
		(at 31.369 -44.958 -90)
		(property "Reference" "C336"
			(at 0 0 270)
			(layer "F.SilkS")
			(hide yes)
			(effects
				(font
					(size 1.27 1.27)
				)
			)
		)
		(property "Value" "SC1U10V2KX-4-GP"
			(at 1.1811 -2.7051 270)
			(unlocked yes)
			(layer "F.Fab")
			(hide yes)
			(effects
				(font
					(size 1.016 1.016)
					(thickness 0.1524)
				)
			)
		)
		(property "Device Type" "C402H22"
			(at 1.1811 -4.2291 270)
			(unlocked yes)
			(layer "F.Fab")
			(hide yes)
			(effects
				(font
					(size 1.016 1.016)
					(thickness 0.1524)
				)
			)
		)
		(duplicate_pad_numbers_are_jumpers no)
		(fp_rect
			(start -0.4318 0.9525)
			(end 0.4318 -0.9525)
			(stroke
				(width 0)
				(type default)
			)
			(fill no)
			(layer "F.CrtYd")
		)
		(fp_rect
			(start -0.4318 0.9525)
			(end 0.4318 -0.9525)
			(stroke
				(width 0)
				(type default)
			)
			(fill no)
			(layer "F.Fab")
		)
		(pad "1" smd custom
			(at 0 -0.4445 270)
			(size 0.1524 0.1524)
			(layers "F.Cu" "F.Mask" "F.Paste")
			(net "P5V_USB")
			(options
				(clearance outline)
				(anchor circle)
			)
			(primitives
				(gr_poly
					(pts
						(arc
							(start 0.3048 -0.2032)
							(mid 0.275042 -0.275042)
							(end 0.2032 -0.3048)
						)
						(arc
							(start -0.2032 -0.3048)
							(mid -0.275042 -0.275042)
							(end -0.3048 -0.2032)
						)
						(arc
							(start -0.3048 0.2032)
							(mid -0.275042 0.275042)
							(end -0.2032 0.3048)
						)
						(arc
							(start 0.2032 0.3048)
							(mid 0.275042 0.275042)
							(end 0.3048 0.2032)
						)
					)
					(width 0)
					(fill yes)
				)
			)
		)
		(pad "2" smd custom
			(at 0 0.4445 270)
			(size 0.1524 0.1524)
			(layers "F.Cu" "F.Mask" "F.Paste")
			(net "GND")
			(options
				(clearance outline)
				(anchor circle)
			)
			(primitives
				(gr_poly
					(pts
						(arc
							(start 0.3048 -0.2032)
							(mid 0.275042 -0.275042)
							(end 0.2032 -0.3048)
						)
						(arc
							(start -0.2032 -0.3048)
							(mid -0.275042 -0.275042)
							(end -0.3048 -0.2032)
						)
						(arc
							(start -0.3048 0.2032)
							(mid -0.275042 0.275042)
							(end -0.2032 0.3048)
						)
						(arc
							(start 0.2032 0.3048)
							(mid 0.275042 0.275042)
							(end 0.3048 0.2032)
						)
					)
					(width 0)
					(fill yes)
				)
			)
		)
	)
	(footprint ""
		(layer "F.Cu")
		(at 66.860166 -86.01456 -90)
		(property "Reference" "C304"
			(at 0 0 270)
			(layer "F.SilkS")
			(hide yes)
			(effects
				(font
					(size 1.27 1.27)
				)
			)
		)
		(property "Value" "SC1U10V2KX-4-GP"
			(at 1.1811 -2.7051 270)
			(unlocked yes)
			(layer "F.Fab")
			(hide yes)
			(effects
				(font
					(size 1.016 1.016)
					(thickness 0.1524)
				)
			)
		)
		(property "Device Type" "C402H22"
			(at 1.1811 -4.2291 270)
			(unlocked yes)
			(layer "F.Fab")
			(hide yes)
			(effects
				(font
					(size 1.016 1.016)
					(thickness 0.1524)
				)
			)
		)
		(duplicate_pad_numbers_are_jumpers no)
		(fp_rect
			(start -0.4318 0.9525)
			(end 0.4318 -0.9525)
			(stroke
				(width 0)
				(type default)
			)
			(fill no)
			(layer "F.CrtYd")
		)
		(fp_rect
			(start -0.4318 0.9525)
			(end 0.4318 -0.9525)
			(stroke
				(width 0)
				(type default)
			)
			(fill no)
			(layer "F.Fab")
		)
		(pad "1" smd custom
			(at 0 -0.4445 270)
			(size 0.1524 0.1524)
			(layers "F.Cu" "F.Mask" "F.Paste")
			(net "HB_A_IN")
			(options
				(clearance outline)
				(anchor circle)
			)
			(primitives
				(gr_poly
					(pts
						(arc
							(start 0.3048 -0.2032)
							(mid 0.275042 -0.275042)
							(end 0.2032 -0.3048)
						)
						(arc
							(start -0.2032 -0.3048)
							(mid -0.275042 -0.275042)
							(end -0.3048 -0.2032)
						)
						(arc
							(start -0.3048 0.2032)
							(mid -0.275042 0.275042)
							(end -0.2032 0.3048)
						)
						(arc
							(start 0.2032 0.3048)
							(mid 0.275042 0.275042)
							(end 0.3048 0.2032)
						)
					)
					(width 0)
					(fill yes)
				)
			)
		)
		(pad "2" smd custom
			(at 0 0.4445 270)
			(size 0.1524 0.1524)
			(layers "F.Cu" "F.Mask" "F.Paste")
			(net "GND")
			(options
				(clearance outline)
				(anchor circle)
			)
			(primitives
				(gr_poly
					(pts
						(arc
							(start 0.3048 -0.2032)
							(mid 0.275042 -0.275042)
							(end 0.2032 -0.3048)
						)
						(arc
							(start -0.2032 -0.3048)
							(mid -0.275042 -0.275042)
							(end -0.3048 -0.2032)
						)
						(arc
							(start -0.3048 0.2032)
							(mid -0.275042 0.275042)
							(end -0.2032 0.3048)
						)
						(arc
							(start 0.2032 0.3048)
							(mid 0.275042 0.275042)
							(end 0.3048 0.2032)
						)
					)
					(width 0)
					(fill yes)
				)
			)
		)
	)
	(footprint ""
		(layer "F.Cu")
		(at 128.078992 -33.5915)
		(property "Reference" "R2933"
			(at 0 0 0)
			(layer "F.SilkS")
			(hide yes)
			(effects
				(font
					(size 1.27 1.27)
				)
			)
		)
		(property "Value" "0R2J-2-GP"
			(at 0.064008 -3.993896 0)
			(unlocked yes)
			(layer "F.Fab")
			(hide yes)
			(effects
				(font
					(size 1.016 1.016)
					(thickness 0.1524)
				)
			)
		)
		(property "Device Type" "R402H16"
			(at 0.064008 -5.517896 0)
			(unlocked yes)
			(layer "F.Fab")
			(hide yes)
			(effects
				(font
					(size 1.016 1.016)
					(thickness 0.1524)
				)
			)
		)
		(duplicate_pad_numbers_are_jumpers no)
		(fp_line
			(start -0.508 -0.9398)
			(end -0.508 0.9398)
			(stroke
				(width 0.1524)
				(type default)
			)
			(layer "F.SilkS")
		)
		(fp_line
			(start 0.508 -0.9398)
			(end -0.508 -0.9398)
			(stroke
				(width 0.1524)
				(type default)
			)
			(layer "F.SilkS")
		)
		(fp_rect
			(start -0.508 0.9398)
			(end 0.508 -0.9398)
			(stroke
				(width 0)
				(type default)
			)
			(fill no)
			(layer "F.CrtYd")
		)
		(fp_rect
			(start -0.508 0.9398)
			(end 0.508 -0.9398)
			(stroke
				(width 0)
				(type default)
			)
			(fill no)
			(layer "F.Fab")
		)
		(pad "1" smd custom
			(at 0 -0.4445)
			(size 0.1397 0.1397)
			(layers "F.Cu" "F.Mask" "F.Paste")
			(net "USB2_BMC_DP")
			(options
				(clearance outline)
				(anchor circle)
			)
			(primitives
				(gr_poly
					(pts
						(arc
							(start -0.1778 -0.2794)
							(mid -0.249642 -0.249642)
							(end -0.2794 -0.1778)
						)
						(arc
							(start -0.2794 0.1778)
							(mid -0.249642 0.249642)
							(end -0.1778 0.2794)
						)
						(arc
							(start 0.1778 0.2794)
							(mid 0.249642 0.249642)
							(end 0.2794 0.1778)
						)
						(arc
							(start 0.2794 -0.1778)
							(mid 0.249642 -0.249642)
							(end 0.1778 -0.2794)
						)
					)
					(width 0)
					(fill yes)
				)
			)
		)
		(pad "2" smd custom
			(at 0 0.4445)
			(size 0.1397 0.1397)
			(layers "F.Cu" "F.Mask" "F.Paste")
			(net "8644_USB_DP1")
			(options
				(clearance outline)
				(anchor circle)
			)
			(primitives
				(gr_poly
					(pts
						(arc
							(start -0.1778 -0.2794)
							(mid -0.249642 -0.249642)
							(end -0.2794 -0.1778)
						)
						(arc
							(start -0.2794 0.1778)
							(mid -0.249642 0.249642)
							(end -0.1778 0.2794)
						)
						(arc
							(start 0.1778 0.2794)
							(mid 0.249642 0.249642)
							(end 0.2794 0.1778)
						)
						(arc
							(start 0.2794 -0.1778)
							(mid 0.249642 -0.249642)
							(end 0.1778 -0.2794)
						)
					)
					(width 0)
					(fill yes)
				)
			)
		)
	)
	(footprint ""
		(layer "F.Cu")
		(at 128.119124 -208.889092 180)
		(property "Reference" "R7970"
			(at 0 0 180)
			(layer "F.SilkS")
			(hide yes)
			(effects
				(font
					(size 1.27 1.27)
				)
			)
		)
		(property "Value" "0R2J-2-GP"
			(at 0.064008 -3.993896 180)
			(unlocked yes)
			(layer "F.Fab")
			(hide yes)
			(effects
				(font
					(size 1.016 1.016)
					(thickness 0.1524)
				)
			)
		)
		(property "Device Type" "R402H16"
			(at 0.064008 -5.517896 180)
			(unlocked yes)
			(layer "F.Fab")
			(hide yes)
			(effects
				(font
					(size 1.016 1.016)
					(thickness 0.1524)
				)
			)
		)
		(duplicate_pad_numbers_are_jumpers no)
		(fp_line
			(start 0.508 -0.9398)
			(end -0.508 -0.9398)
			(stroke
				(width 0.1524)
				(type default)
			)
			(layer "F.SilkS")
		)
		(fp_line
			(start -0.508 -0.9398)
			(end -0.508 0.9398)
			(stroke
				(width 0.1524)
				(type default)
			)
			(layer "F.SilkS")
		)
		(fp_rect
			(start -0.508 0.9398)
			(end 0.508 -0.9398)
			(stroke
				(width 0)
				(type default)
			)
			(fill no)
			(layer "F.CrtYd")
		)
		(fp_rect
			(start -0.508 0.9398)
			(end 0.508 -0.9398)
			(stroke
				(width 0)
				(type default)
			)
			(fill no)
			(layer "F.Fab")
		)
		(pad "1" smd custom
			(at 0 -0.4445 180)
			(size 0.1397 0.1397)
			(layers "F.Cu" "F.Mask" "F.Paste")
			(net "SSD_PERST#7")
			(options
				(clearance outline)
				(anchor circle)
			)
			(primitives
				(gr_poly
					(pts
						(arc
							(start -0.1778 -0.2794)
							(mid -0.249642 -0.249642)
							(end -0.2794 -0.1778)
						)
						(arc
							(start -0.2794 0.1778)
							(mid -0.249642 0.249642)
							(end -0.1778 0.2794)
						)
						(arc
							(start 0.1778 0.2794)
							(mid 0.249642 0.249642)
							(end 0.2794 0.1778)
						)
						(arc
							(start 0.2794 -0.1778)
							(mid 0.249642 -0.249642)
							(end 0.1778 -0.2794)
						)
					)
					(width 0)
					(fill yes)
				)
			)
		)
		(pad "2" smd custom
			(at 0 0.4445 180)
			(size 0.1397 0.1397)
			(layers "F.Cu" "F.Mask" "F.Paste")
			(net "SSD_PERST#7_R")
			(options
				(clearance outline)
				(anchor circle)
			)
			(primitives
				(gr_poly
					(pts
						(arc
							(start -0.1778 -0.2794)
							(mid -0.249642 -0.249642)
							(end -0.2794 -0.1778)
						)
						(arc
							(start -0.2794 0.1778)
							(mid -0.249642 0.249642)
							(end -0.1778 0.2794)
						)
						(arc
							(start 0.1778 0.2794)
							(mid 0.249642 0.249642)
							(end 0.2794 0.1778)
						)
						(arc
							(start 0.2794 -0.1778)
							(mid 0.249642 -0.249642)
							(end 0.1778 -0.2794)
						)
					)
					(width 0)
					(fill yes)
				)
			)
		)
	)
	(footprint ""
		(layer "F.Cu")
		(at 123.928124 -208.889092)
		(property "Reference" "R7915"
			(at 0 0 0)
			(layer "F.SilkS")
			(hide yes)
			(effects
				(font
					(size 1.27 1.27)
				)
			)
		)
		(property "Value" "0R2J-2-GP"
			(at 0.064008 -3.993896 0)
			(unlocked yes)
			(layer "F.Fab")
			(hide yes)
			(effects
				(font
					(size 1.016 1.016)
					(thickness 0.1524)
				)
			)
		)
		(property "Device Type" "R402H16"
			(at 0.064008 -5.517896 0)
			(unlocked yes)
			(layer "F.Fab")
			(hide yes)
			(effects
				(font
					(size 1.016 1.016)
					(thickness 0.1524)
				)
			)
		)
		(duplicate_pad_numbers_are_jumpers no)
		(fp_line
			(start -0.508 -0.9398)
			(end -0.508 0.9398)
			(stroke
				(width 0.1524)
				(type default)
			)
			(layer "F.SilkS")
		)
		(fp_line
			(start 0.508 -0.9398)
			(end -0.508 -0.9398)
			(stroke
				(width 0.1524)
				(type default)
			)
			(layer "F.SilkS")
		)
		(fp_rect
			(start -0.508 0.9398)
			(end 0.508 -0.9398)
			(stroke
				(width 0)
				(type default)
			)
			(fill no)
			(layer "F.CrtYd")
		)
		(fp_rect
			(start -0.508 0.9398)
			(end 0.508 -0.9398)
			(stroke
				(width 0)
				(type default)
			)
			(fill no)
			(layer "F.Fab")
		)
		(pad "1" smd custom
			(at 0 -0.4445)
			(size 0.1397 0.1397)
			(layers "F.Cu" "F.Mask" "F.Paste")
			(net "TWI_SDA1")
			(options
				(clearance outline)
				(anchor circle)
			)
			(primitives
				(gr_poly
					(pts
						(arc
							(start -0.1778 -0.2794)
							(mid -0.249642 -0.249642)
							(end -0.2794 -0.1778)
						)
						(arc
							(start -0.2794 0.1778)
							(mid -0.249642 0.249642)
							(end -0.1778 0.2794)
						)
						(arc
							(start 0.1778 0.2794)
							(mid 0.249642 0.249642)
							(end 0.2794 0.1778)
						)
						(arc
							(start 0.2794 -0.1778)
							(mid 0.249642 -0.249642)
							(end 0.1778 -0.2794)
						)
					)
					(width 0)
					(fill yes)
				)
			)
		)
		(pad "2" smd custom
			(at 0 0.4445)
			(size 0.1397 0.1397)
			(layers "F.Cu" "F.Mask" "F.Paste")
			(net "I2C_GPIO_SDA_2")
			(options
				(clearance outline)
				(anchor circle)
			)
			(primitives
				(gr_poly
					(pts
						(arc
							(start -0.1778 -0.2794)
							(mid -0.249642 -0.249642)
							(end -0.2794 -0.1778)
						)
						(arc
							(start -0.2794 0.1778)
							(mid -0.249642 0.249642)
							(end -0.1778 0.2794)
						)
						(arc
							(start 0.1778 0.2794)
							(mid 0.249642 0.249642)
							(end 0.2794 0.1778)
						)
						(arc
							(start 0.2794 -0.1778)
							(mid 0.249642 -0.249642)
							(end 0.1778 -0.2794)
						)
					)
					(width 0)
					(fill yes)
				)
			)
		)
	)
	(footprint ""
		(layer "F.Cu")
		(at 322.79209 -212.420454 180)
		(property "Reference" "C64"
			(at 0 0 180)
			(layer "F.SilkS")
			(hide yes)
			(effects
				(font
					(size 1.27 1.27)
				)
			)
		)
		(property "Value" "SCD22U10V2KX-1GP"
			(at 1.1811 -2.7051 180)
			(unlocked yes)
			(layer "F.Fab")
			(hide yes)
			(effects
				(font
					(size 1.016 1.016)
					(thickness 0.1524)
				)
			)
		)
		(property "Device Type" "C402H22"
			(at 1.1811 -4.2291 180)
			(unlocked yes)
			(layer "F.Fab")
			(hide yes)
			(effects
				(font
					(size 1.016 1.016)
					(thickness 0.1524)
				)
			)
		)
		(duplicate_pad_numbers_are_jumpers no)
		(fp_rect
			(start -0.4318 0.9525)
			(end 0.4318 -0.9525)
			(stroke
				(width 0)
				(type default)
			)
			(fill no)
			(layer "F.CrtYd")
		)
		(fp_rect
			(start -0.4318 0.9525)
			(end 0.4318 -0.9525)
			(stroke
				(width 0)
				(type default)
			)
			(fill no)
			(layer "F.Fab")
		)
		(pad "1" smd custom
			(at 0 -0.4445 180)
			(size 0.1524 0.1524)
			(layers "F.Cu" "F.Mask" "F.Paste")
			(net "PCIE_TX_CAP_P21")
			(options
				(clearance outline)
				(anchor circle)
			)
			(primitives
				(gr_poly
					(pts
						(arc
							(start 0.3048 -0.2032)
							(mid 0.275042 -0.275042)
							(end 0.2032 -0.3048)
						)
						(arc
							(start -0.2032 -0.3048)
							(mid -0.275042 -0.275042)
							(end -0.3048 -0.2032)
						)
						(arc
							(start -0.3048 0.2032)
							(mid -0.275042 0.275042)
							(end -0.2032 0.3048)
						)
						(arc
							(start 0.2032 0.3048)
							(mid 0.275042 0.275042)
							(end 0.3048 0.2032)
						)
					)
					(width 0)
					(fill yes)
				)
			)
		)
		(pad "2" smd custom
			(at 0 0.4445 180)
			(size 0.1524 0.1524)
			(layers "F.Cu" "F.Mask" "F.Paste")
			(net "PCIE_TX_P21")
			(options
				(clearance outline)
				(anchor circle)
			)
			(primitives
				(gr_poly
					(pts
						(arc
							(start 0.3048 -0.2032)
							(mid 0.275042 -0.275042)
							(end 0.2032 -0.3048)
						)
						(arc
							(start -0.2032 -0.3048)
							(mid -0.275042 -0.275042)
							(end -0.3048 -0.2032)
						)
						(arc
							(start -0.3048 0.2032)
							(mid -0.275042 0.275042)
							(end -0.2032 0.3048)
						)
						(arc
							(start 0.2032 0.3048)
							(mid 0.275042 0.275042)
							(end 0.3048 0.2032)
						)
					)
					(width 0)
					(fill yes)
				)
			)
		)
	)
)
